P  UNITS CUST 0
C   
C   IPC 356 OUTPUT.  
C
317$NONE$                       D0768PA00X+052451Y+020874               S0      
317$NONE$                       D0768PA00X+035916Y+020874               S0      
317$NONE$                       D0530PA00X+051614Y+020874               S0      
317$NONE$                       D0197PA00X+043433Y+020374               S0      
317$NONE$                       D0197PA00X+043933Y+020374               S0      
317$NONE$                       D0197PA00X+044433Y+020374               S0      
317$NONE$                       D0157PA00X+041553Y+021717               S0      
317$NONE$                       D0157PA00X+041868Y+021717               S0      
317$NONE$                       D0157PA00X+042183Y+021717               S0      
317$NONE$                       D0157PA00X+042498Y+021717               S0      
317$NONE$                       D0157PA00X+042813Y+021717               S0      
317$NONE$                       D0768PA00X+052451Y+014299               S0      
317$NONE$                       D0768PA00X+035916Y+014299               S0      
317$NONE$                       D0530PA00X+051614Y+014299               S0      
317$NONE$                       D0197PA00X+043433Y+013799               S0      
317$NONE$                       D0197PA00X+043933Y+013799               S0      
317$NONE$                       D0197PA00X+044433Y+013799               S0      
317$NONE$                       D0157PA00X+041553Y+015142               S0      
317$NONE$                       D0157PA00X+041868Y+015142               S0      
317$NONE$                       D0157PA00X+042183Y+015142               S0      
317$NONE$                       D0157PA00X+042498Y+015142               S0      
317$NONE$                       D0157PA00X+042813Y+015142               S0      
317$NONE$                       D0768PA00X+023346Y+005953               S0      
317$NONE$                       D0768PA00X+006811Y+005953               S0      
317$NONE$                       D0530PA00X+022510Y+005953               S0      
317$NONE$                       D0197PA00X+014329Y+005453               S0      
317$NONE$                       D0197PA00X+014829Y+005453               S0      
317$NONE$                       D0197PA00X+015329Y+005453               S0      
317$NONE$                       D0157PA00X+012449Y+006795               S0      
317$NONE$                       D0157PA00X+012764Y+006795               S0      
317$NONE$                       D0157PA00X+013079Y+006795               S0      
317$NONE$                       D0157PA00X+013394Y+006795               S0      
317$NONE$                       D0157PA00X+013709Y+006795               S0      
317$NONE$                       D0768PA00X+023346Y+001504               S0      
317$NONE$                       D0768PA00X+006811Y+001504               S0      
317$NONE$                       D0530PA00X+022510Y+001504               S0      
317$NONE$                       D0197PA00X+014329Y+001004               S0      
317$NONE$                       D0197PA00X+014829Y+001004               S0      
317$NONE$                       D0197PA00X+015329Y+001004               S0      
317$NONE$                       D0157PA00X+012449Y+002346               S0      
317$NONE$                       D0157PA00X+012764Y+002346               S0      
317$NONE$                       D0157PA00X+013079Y+002346               S0      
317$NONE$                       D0157PA00X+013394Y+002346               S0      
317$NONE$                       D0157PA00X+013709Y+002346               S0      
317$NONE$                       D0400PA01X+002085Y+070160               S0      
317$NONE$                       D0400PA01X+003274Y+003046               S0      
317$NONE$                       D0400PA01X+051436Y+005761               S0      
327$NONE$                             A01X+033200Y+023450X2720Y2720     S0      
317$NONE$                       D0860PA00X-001245Y+004551               S0      
317$NONE$                       D0860PA00X-001475Y+041556               S0      
317$NONE$                       D0860PA00X+014147Y+065536               S0      
317$NONE$                       D0860PA00X+002946Y+071885               S0      
317$NONE$                       D0860PA00X+039594Y+007670               S0      
317$NONE$                       D0860PA00X+050857Y+001509               S0      
317$NONE$                       D0860PA00X+055413Y+031594               S0      
317$NONE$                       D0860PA00X+055413Y+068562               S0      
317$NONE$                       D0200PA00X+033059Y+006557               S0      
317$NONE$                       D0200PA00X+029547Y+006557               S0      
317$NONE$                       D0200PA00X+033059Y+010829               S0      
317$NONE$                       D0200PA00X+029547Y+010829               S0      
327$NONE$                             A06X+029758Y+007512X0470Y0140     S0      
327$NONE$                             A06X+029758Y+007807X0470Y0140     S0      
327$NONE$                             A06X+030821Y+007512X0470Y0140     S0      
327$NONE$                             A06X+030821Y+007807X0470Y0140     S0      
327$NONE$                             A06X+032211Y+007512X0470Y0140     S0      
327$NONE$                             A06X+032211Y+007807X0470Y0140     S0      
327$NONE$                             A06X+033274Y+007512X0470Y0140     S0      
327$NONE$                             A06X+033274Y+007807X0470Y0140     S0      
317$NONE$                       D0480PA00X+031266Y+006614               S0      
317$NONE$                       D0480PA00X+031266Y+010772               S0      
317$NONE$                       D0500PA00X+047315Y+007909               S0      
317$NONE$                       D0500PA00X+053221Y+007909               S0      
317$NONE$           VIA        MD0100PA01X+052559Y+024094               S0      
317$NONE$           VIA        MD0100PA06X+052559Y+024094               S0      
317$NONE$           VIA        MD0100PA01X+055280Y+004016               S0      
317$NONE$           VIA        MD0100PA06X+055280Y+004016               S0      
317$NONE$           VIA        MD0100PA01X+001772Y+004409               S0      
317$NONE$           VIA        MD0100PA06X+001772Y+004409               S0      
317HBA_PRSNT1_N                 D0240PA01X+050287Y+015949               S0      
317HBA_PRSNT1_N                 D0197PA00X+047933Y+013799               S0      
317HBA_PRSNT1_N                 D0220PA01X+050687Y+015959               S0      
327HBA_PRSNT1_N                       A06X+005472Y+007205X0630Y0240     S0      
327HBA_PRSNT1_N                       A06X+032000Y+021975X0160Y0480     S0      
317HBA_PRSNT1_N     VIA        MD0280PA06X+028850Y+020717               S0      
317HBA_PRSNT1_N     VIA        MD0100PA00X+020450Y+009000               S0      
317HBA_PRSNT1_N     VIA        MD0100PA00X+027944Y+012073               S0      
317GND                          D1300PA00X+001575Y+006701               S0      
317GND                          D1300PA00X+030315Y+024291               S0      
317GND                          D1300PA00X+030315Y+001378               S0      
317GND                          D1300PA00X+055118Y+001378               S0      
317GND                          D1660PA00X+001575Y+001583               S0      
317GND                          D1660PA00X+055118Y+024291               S0      
317GND                          D0240PA01X+032095Y+004643               S0      
317GND                          D0240PA01X+020427Y+003894               S0      
317GND                          D0240PA01X+020043Y+008186               S0      
317GND                          D0240PA01X+021110Y+003560               S0      
317GND                          D0240PA01X+022216Y+003830               S0      
317GND                          D0240PA01X+032442Y+004642               S0      
317GND                          D0240PA01X+030420Y+020600               S0      
317GND                          D0240PA01X+030420Y+020950               S0      
317GND                          D0240PA01X+004470Y+007950               S0      
317GND                          D0240PA01X+004470Y+007600               S0      
317GND                          D0240PA01X+021783Y+007936               S0      
317GND                          D0240PA01X+029310Y+016480               S0      
317GND                          D0240PA01X+047990Y+022730               S0      
317GND                          D0240PA01X+020750Y+007830               S0      
317GND                          D0240PA01X+050287Y+016309               S0      
327GND                                A01X+023963Y+007686X0500Y0650     S0      
327GND                                A01X+023963Y+008556X0500Y0650     S0      
327GND                                A01X+024446Y+003330X0500Y0650     S0      
327GND                                A01X+028980Y+015870X0500Y0650     S0      
327GND                                A01X+028980Y+015000X0500Y0650     S0      
327GND                                A01X+024446Y+004200X0500Y0650     S0      
327GND                                A01X+020596Y+003340X0450Y0550     S0      
327GND                                A01X+020243Y+007636X0450Y0550     S0      
327GND                                A01X+030220Y+020050X0450Y0550     S0      
327GND                                A01X+030220Y+019250X0450Y0550     S0      
317GND                          D0197PA00X+044933Y+020374               S0      
317GND                          D0197PA00X+045433Y+020374               S0      
317GND                          D0197PA00X+045933Y+020374               S0      
317GND                          D0197PA00X+048933Y+020374               S0      
317GND                          D0197PA00X+037933Y+020374               S0      
317GND                          D0197PA00X+039433Y+020374               S0      
317GND                          D0197PA00X+040933Y+020374               S0      
317GND                          D0157PA00X+041238Y+021717               S0      
317GND                          D0157PA00X+043128Y+021717               S0      
317GND                          D0197PA00X+044933Y+013799               S0      
317GND                          D0197PA00X+045433Y+013799               S0      
317GND                          D0197PA00X+045933Y+013799               S0      
317GND                          D0197PA00X+048933Y+013799               S0      
317GND                          D0197PA00X+037933Y+013799               S0      
317GND                          D0197PA00X+039433Y+013799               S0      
317GND                          D0197PA00X+040933Y+013799               S0      
317GND                          D0157PA00X+041238Y+015142               S0      
317GND                          D0157PA00X+043128Y+015142               S0      
317GND                          D0197PA00X+015829Y+005453               S0      
317GND                          D0197PA00X+016329Y+005453               S0      
317GND                          D0197PA00X+016829Y+005453               S0      
317GND                          D0197PA00X+019829Y+005453               S0      
317GND                          D0197PA00X+008829Y+005453               S0      
317GND                          D0197PA00X+010329Y+005453               S0      
317GND                          D0197PA00X+011829Y+005453               S0      
317GND                          D0157PA00X+012134Y+006795               S0      
317GND                          D0157PA00X+014024Y+006795               S0      
317GND                          D0197PA00X+015829Y+001004               S0      
317GND                          D0197PA00X+016329Y+001004               S0      
317GND                          D0197PA00X+016829Y+001004               S0      
317GND                          D0197PA00X+019829Y+001004               S0      
317GND                          D0197PA00X+008829Y+001004               S0      
317GND                          D0197PA00X+010329Y+001004               S0      
317GND                          D0197PA00X+011829Y+001004               S0      
317GND                          D0157PA00X+012134Y+002346               S0      
317GND                          D0157PA00X+014024Y+002346               S0      
317GND                          D0220PA01X+031670Y+003200               S0      
327GND                                A06X+029758Y+008102X0470Y0140     S0      
327GND                                A06X+029758Y+008988X0470Y0140     S0      
327GND                                A06X+029758Y+009874X0470Y0140     S0      
327GND                                A06X+030821Y+008102X0470Y0140     S0      
327GND                                A06X+030821Y+008988X0470Y0140     S0      
327GND                                A06X+030821Y+009874X0470Y0140     S0      
327GND                                A06X+032211Y+008102X0470Y0140     S0      
327GND                                A06X+032211Y+008988X0470Y0140     S0      
327GND                                A06X+032211Y+009874X0470Y0140     S0      
327GND                                A06X+033274Y+008102X0470Y0140     S0      
327GND                                A06X+033274Y+008988X0470Y0140     S0      
327GND                                A06X+033274Y+009874X0470Y0140     S0      
317GND                          D0240PA06X+032234Y+005092               S0      
317GND                          D0240PA06X+051600Y+010678               S0      
317GND                          D0240PA06X+048895Y+010679               S0      
317GND                          D0240PA06X+029310Y+016480               S0      
317GND                          D0240PA06X+028108Y+003003               S0      
317GND                          D0240PA06X+032803Y+017983               S0      
327GND                                A06X+032562Y+005670X0400Y0220     S0      
327GND                                A06X+028980Y+015870X0500Y0650     S0      
327GND                                A06X+028980Y+015000X0500Y0650     S0      
327GND                                A06X+049112Y+010110X0450Y0550     S0      
327GND                                A06X+051396Y+010103X0450Y0550     S0      
327GND                                A06X+005472Y+006024X0630Y0240     S0      
327GND                                A06X+005472Y+005630X0630Y0240     S0      
327GND                                A06X+005472Y+005236X0630Y0240     S0      
327GND                                A06X+005472Y+003268X0630Y0240     S0      
327GND                                A06X+005472Y+002874X0630Y0240     S0      
327GND                                A06X+005472Y+002480X0630Y0240     S0      
327GND                                A06X+004469Y+008504X0710Y0320     S0      
327GND                                A06X+004469Y+001969X0710Y0320     S0      
317GND                          D0460PA00X+049677Y+008681               S0      
317GND                          D0460PA00X+050858Y+008681               S0      
327GND                                A06X+030694Y+014070X0160Y0400     S0      
327GND                                A06X+031206Y+013330X0160Y0400     S0      
327GND                                A06X+033744Y+002770X0160Y0400     S0      
327GND                                A06X+034256Y+002030X0160Y0400     S0      
327GND                                A06X+031640Y+003300X0160Y0400     S0      
327GND                                A06X+032256Y+021975X0160Y0480     S0      
327GND                                A06X+030646Y+003945X0160Y0480     S0      
317GND                          D0340PA06X+030740Y+004630               S0      
317GND                          D0300PA06X+032310Y+018044               S0      
317GND                          D0300PA06X+027610Y+002982               S0      
317GND              VIA        MD0280PA06X+033184Y+023332               S0      
317GND              VIA        MD0280PA06X+054763Y+021532               S0      
317GND              VIA        MD0280PA06X+054981Y+008995               S0      
317GND              VIA        MD0280PA01X+027124Y+006721               S0      
317GND              VIA        MD0100PA00X+021788Y+008360               S0      
317GND              VIA        MD0100PA00X+022221Y+004150               S0      
317GND              VIA        MD0100PA00X+029314Y+009800               S0      
317GND              VIA        MD0100PA00X+029315Y+008102               S0      
317GND              VIA        MD0100PA00X+030373Y+008988               S0      
317GND              VIA        MD0100PA00X+030821Y+010195               S0      
317GND              VIA        MD0100PA00X+031362Y+008102               S0      
317GND              VIA        MD0100PA00X+032144Y+010157               S0      
317GND              VIA        MD0100PA00X+032689Y+007937               S0      
317GND              VIA        MD0100PA00X+032706Y+009094               S0      
317GND              VIA        MD0100PA00X+032996Y+005670               S0      
317GND              VIA        MD0100PA00X+033282Y+010314               S0      
317GND              VIA        MD0100PA00X+033741Y+007958               S0      
317GND              VIA        MD0100PA00X+033767Y+009098               S0      
317GND              VIA        MD0100PA00X+033815Y+009874               S0      
317GND              VIA        MD0100PA00X+034113Y+008030               S0      
317GND              VIA        MD0100PA00X+034564Y+009013               S0      
317GND              VIA        MD0120PA00X+010796Y+008584               S0      
317GND              VIA        MD0120PA00X+012796Y+008584               S0      
317GND              VIA        MD0120PA00X+014796Y+008584               S0      
317GND              VIA        MD0120PA00X+016796Y+008584               S0      
317GND              VIA        MD0120PA00X+018796Y+008584               S0      
317GND              VIA        MD0120PA00X+020400Y+008200               S0      
317GND              VIA        MD0120PA00X+020400Y+008600               S0      
317GND              VIA        MD0120PA00X+020768Y+003891               S0      
317GND              VIA        MD0120PA00X+020800Y+008200               S0      
317GND              VIA        MD0120PA00X+020800Y+008600               S0      
317GND              VIA        MD0120PA00X+021134Y+003896               S0      
317GND              VIA        MD0120PA00X+021491Y+003949               S0      
317GND              VIA        MD0120PA00X+024250Y+002700               S0      
317GND              VIA        MD0120PA00X+024300Y+004750               S0      
317GND              VIA        MD0120PA00X+024473Y+007659               S0      
317GND              VIA        MD0120PA00X+024487Y+008037               S0      
317GND              VIA        MD0120PA00X+024650Y+002700               S0      
317GND              VIA        MD0120PA00X+024700Y+004750               S0      
317GND              VIA        MD0120PA00X+024881Y+008027               S0      
317GND              VIA        MD0120PA00X+024887Y+007646               S0      
317GND              VIA        MD0120PA00X+002796Y+008584               S0      
317GND              VIA        MD0120PA00X+027912Y+017421               S0      
317GND              VIA        MD0120PA00X+027912Y+019421               S0      
317GND              VIA        MD0120PA00X+027912Y+021421               S0      
317GND              VIA        MD0120PA00X+027912Y+023421               S0      
317GND              VIA        MD0120PA00X+028122Y+003397               S0      
317GND              VIA        MD0120PA00X+028214Y+025119               S0      
317GND              VIA        MD0120PA00X+028480Y+014906               S0      
317GND              VIA        MD0120PA00X+028480Y+015269               S0      
317GND              VIA        MD0120PA00X+028491Y+016054               S0      
317GND              VIA        MD0120PA00X+028494Y+015688               S0      
317GND              VIA        MD0120PA00X+028980Y+016500               S0      
317GND              VIA        MD0120PA00X+029770Y+019156               S0      
317GND              VIA        MD0120PA00X+029770Y+019519               S0      
317GND              VIA        MD0120PA00X+029781Y+020304               S0      
317GND              VIA        MD0120PA00X+029784Y+019938               S0      
317GND              VIA        MD0120PA00X+030075Y+020596               S0      
317GND              VIA        MD0120PA00X+030370Y+014070               S0      
317GND              VIA        MD0120PA00X+030400Y+021300               S0      
317GND              VIA        MD0120PA00X+031505Y+013330               S0      
317GND              VIA        MD0120PA00X+032137Y+005670               S0      
317GND              VIA        MD0120PA00X+032214Y+025119               S0      
317GND              VIA        MD0120PA00X+032270Y+000550               S0      
317GND              VIA        MD0120PA00X+032600Y+021750               S0      
317GND              VIA        MD0120PA00X+032642Y+018363               S0      
317GND              VIA        MD0120PA00X+033267Y+002770               S0      
317GND              VIA        MD0120PA00X+034214Y+025119               S0      
317GND              VIA        MD0120PA00X+034569Y+002030               S0      
317GND              VIA        MD0120PA00X+035767Y+000460               S0      
317GND              VIA        MD0120PA00X+036214Y+025119               S0      
317GND              VIA        MD0120PA00X+003700Y+007550               S0      
317GND              VIA        MD0120PA00X+003700Y+007950               S0      
317GND              VIA        MD0120PA00X+038214Y+025119               S0      
317GND              VIA        MD0120PA00X+040214Y+025119               S0      
317GND              VIA        MD0120PA00X+004100Y+007550               S0      
317GND              VIA        MD0120PA00X+004100Y+007950               S0      
317GND              VIA        MD0120PA00X+042214Y+025119               S0      
317GND              VIA        MD0120PA00X+004270Y+000550               S0      
317GND              VIA        MD0120PA00X+004428Y+002472               S0      
317GND              VIA        MD0120PA00X+044214Y+025119               S0      
317GND              VIA        MD0120PA00X+004432Y+002868               S0      
317GND              VIA        MD0120PA00X+004432Y+003253               S0      
317GND              VIA        MD0120PA00X+004534Y+005243               S0      
317GND              VIA        MD0120PA00X+004537Y+005639               S0      
317GND              VIA        MD0120PA00X+004537Y+006024               S0      
317GND              VIA        MD0120PA00X+046214Y+025119               S0      
317GND              VIA        MD0120PA00X+047145Y+009335               S0      
317GND              VIA        MD0120PA00X+047660Y+022725               S0      
317GND              VIA        MD0120PA00X+004828Y+002472               S0      
317GND              VIA        MD0120PA00X+048214Y+025119               S0      
317GND              VIA        MD0120PA00X+004832Y+002868               S0      
317GND              VIA        MD0120PA00X+004832Y+003253               S0      
317GND              VIA        MD0120PA00X+004934Y+005243               S0      
317GND              VIA        MD0120PA00X+004937Y+005639               S0      
317GND              VIA        MD0120PA00X+004937Y+006024               S0      
317GND              VIA        MD0120PA00X+050214Y+025119               S0      
317GND              VIA        MD0120PA00X+050287Y+016645               S0      
317GND              VIA        MD0120PA00X+051998Y+022630               S0      
317GND              VIA        MD0120PA00X+052002Y+023007               S0      
317GND              VIA        MD0120PA00X+052214Y+025119               S0      
317GND              VIA        MD0120PA00X+052364Y+022635               S0      
317GND              VIA        MD0120PA00X+052364Y+023001               S0      
317GND              VIA        MD0120PA00X+053896Y+004199               S0      
317GND              VIA        MD0120PA00X+053896Y+006199               S0      
317GND              VIA        MD0120PA00X+000550Y+004830               S0      
317GND              VIA        MD0120PA00X+055946Y+010851               S0      
317GND              VIA        MD0120PA00X+055946Y+012851               S0      
317GND              VIA        MD0120PA00X+055946Y+014851               S0      
317GND              VIA        MD0120PA00X+055946Y+016851               S0      
317GND              VIA        MD0120PA00X+055946Y+018851               S0      
317GND              VIA        MD0120PA00X+055946Y+020851               S0      
317GND              VIA        MD0120PA00X+055946Y+006851               S0      
317GND              VIA        MD0120PA00X+055946Y+008851               S0      
317GND              VIA        MD0120PA00X+006796Y+008584               S0      
317GND              VIA        MD0120PA00X+000796Y+008584               S0      
317GND              VIA        MD0120PA00X+008796Y+008584               S0      
317P12V_SW_R                    D0340PA01X+049745Y+022405               S0      
317P12V_SW_R                    D0340PA01X+051730Y+015850               S0      
317P12V_SW_R                    D0240PA01X+029670Y+016480               S0      
327P12V_SW_R                          A01X+030080Y+015870X0500Y0650     S0      
327P12V_SW_R                          A01X+030080Y+015000X0500Y0650     S0      
317P12V_SW_R                    D0197PA00X+049933Y+020374               S0      
317P12V_SW_R                    D0197PA00X+050433Y+020374               S0      
317P12V_SW_R                    D0197PA00X+049933Y+013799               S0      
317P12V_SW_R                    D0197PA00X+050433Y+013799               S0      
327P12V_SW_R                          A01X+032469Y+016213X0450Y0550     S0      
317P12V_SW_R                    D0240PA06X+029670Y+016480               S0      
327P12V_SW_R                          A06X+030080Y+015870X0500Y0650     S0      
327P12V_SW_R                          A06X+030080Y+015000X0500Y0650     S0      
327P12V_SW_R                          A06X+030900Y+014950X0650Y0250     S0      
327P12V_SW_R                          A06X+030900Y+015450X0650Y0250     S0      
327P12V_SW_R                          A06X+030900Y+015950X0650Y0250     S0      
327P12V_SW_R                          A06X+030900Y+016450X0650Y0250     S0      
317P12V_SW_R        VIA        MD0280PA01X+031050Y+015200               S0      
317P12V_SW_R        VIA        MD0120PA00X+029930Y+014450               S0      
317P12V_SW_R        VIA        MD0120PA00X+030000Y+016490               S0      
317P12V_SW_R        VIA        MD0120PA00X+030300Y+014440               S0      
317P12V_SW_R        VIA        MD0120PA00X+030360Y+016480               S0      
317P12V_SW_R        VIA        MD0120PA00X+031633Y+015567               S0      
317P12V_SW_R        VIA        MD0120PA00X+031633Y+016002               S0      
317P12V_SW_R        VIA        MD0120PA00X+031633Y+016452               S0      
317P12V_SW_R        VIA        MD0120PA00X+031644Y+015144               S0      
317P12V_SW_R        VIA        MD0120PA00X+032033Y+015567               S0      
317P12V_SW_R        VIA        MD0120PA00X+032033Y+016002               S0      
317P12V_SW_R        VIA        MD0120PA00X+032033Y+016452               S0      
317P12V_SW_R        VIA        MD0120PA00X+032044Y+015144               S0      
317HBA_PRSNT2_N                 D0240PA01X+020750Y+007470               S0      
317HBA_PRSNT2_N                 D0197PA00X+018829Y+005453               S0      
317HBA_PRSNT2_N                 D0220PA01X+021150Y+007480               S0      
327HBA_PRSNT2_N                       A06X+005472Y+006811X0630Y0240     S0      
327HBA_PRSNT2_N                       A06X+030134Y+003945X0160Y0480     S0      
317HBA_PRSNT2_N     VIA        MD0280PA06X+026194Y+001086               S0      
317HBA_PRSNT2_N     VIA        MD0100PA00X+007680Y+006170               S0      
317HBA_PRSNT3_N                 D0240PA01X+021110Y+003200               S0      
317HBA_PRSNT3_N                 D0197PA00X+018829Y+001004               S0      
317HBA_PRSNT3_N                 D0220PA01X+021496Y+003210               S0      
327HBA_PRSNT3_N                       A06X+005472Y+006417X0630Y0240     S0      
327HBA_PRSNT3_N                       A06X+030390Y+003945X0160Y0480     S0      
317HBA_PRSNT3_N     VIA        MD0280PA06X+026140Y+001885               S0      
317HBA_PRSNT3_N     VIA        MD0100PA00X+006093Y+006417               S0      
317P5V_SW_L                     D0340PA01X+019250Y+003210               S0      
317P5V_SW_L                     D0340PA01X+018830Y+007500               S0      
317P5V_SW_L                     D0240PA01X+020067Y+003894               S0      
317P5V_SW_L                     D0240PA01X+019683Y+008186               S0      
327P5V_SW_L                           A01X+019836Y+003340X0450Y0550     S0      
327P5V_SW_L                           A01X+019483Y+007636X0450Y0550     S0      
317P5V_SW_L                     D0197PA00X+017829Y+005453               S0      
317P5V_SW_L                     D0197PA00X+018329Y+005453               S0      
317P5V_SW_L                     D0197PA00X+017829Y+001004               S0      
317P5V_SW_L                     D0197PA00X+018329Y+001004               S0      
327P5V_SW_L                           A01X+026629Y+004856X0450Y0550     S0      
327P5V_SW_L                           A06X+026750Y+003750X0650Y0250     S0      
327P5V_SW_L                           A06X+026750Y+004250X0650Y0250     S0      
327P5V_SW_L                           A06X+026750Y+004750X0650Y0250     S0      
327P5V_SW_L                           A06X+026750Y+005250X0650Y0250     S0      
317P5V_SW_L         VIA        MD0280PA01X+026715Y+003940               S0      
317P5V_SW_L         VIA        MD0120PA00X+025812Y+005231               S0      
317P5V_SW_L         VIA        MD0120PA00X+025817Y+004851               S0      
317P5V_SW_L         VIA        MD0120PA00X+025824Y+004226               S0      
317P5V_SW_L         VIA        MD0120PA00X+025832Y+003848               S0      
317P5V_SW_L         VIA        MD0120PA00X+026172Y+005231               S0      
317P5V_SW_L         VIA        MD0120PA00X+026177Y+004851               S0      
317P5V_SW_L         VIA        MD0120PA00X+026184Y+004226               S0      
317P5V_SW_L         VIA        MD0120PA00X+026192Y+003848               S0      
317P12V_SW_L                    D0340PA01X+022219Y+007496               S0      
317P12V_SW_L                    D0340PA01X+022652Y+003390               S0      
317P12V_SW_L                    D0240PA01X+022576Y+003830               S0      
317P12V_SW_L                    D0240PA01X+022143Y+007936               S0      
327P12V_SW_L                          A01X+022863Y+007686X0500Y0650     S0      
327P12V_SW_L                          A01X+022863Y+008556X0500Y0650     S0      
327P12V_SW_L                          A01X+023346Y+003330X0500Y0650     S0      
327P12V_SW_L                          A01X+023346Y+004200X0500Y0650     S0      
317P12V_SW_L                    D0197PA00X+020829Y+005453               S0      
317P12V_SW_L                    D0197PA00X+021329Y+005453               S0      
317P12V_SW_L                    D0197PA00X+020829Y+001004               S0      
317P12V_SW_L                    D0197PA00X+021329Y+001004               S0      
327P12V_SW_L                          A01X+033701Y+004433X0450Y0550     S0      
327P12V_SW_L                          A06X+033863Y+003705X0650Y0250     S0      
327P12V_SW_L                          A06X+033863Y+004205X0650Y0250     S0      
327P12V_SW_L                          A06X+033863Y+004705X0650Y0250     S0      
327P12V_SW_L                          A06X+033863Y+005205X0650Y0250     S0      
317P12V_SW_L        VIA        MD0280PA01X+033692Y+005188               S0      
317P12V_SW_L        VIA        MD0120PA00X+032842Y+004541               S0      
317P12V_SW_L        VIA        MD0120PA00X+032851Y+004163               S0      
317P12V_SW_L        VIA        MD0120PA00X+032857Y+004903               S0      
317P12V_SW_L        VIA        MD0120PA00X+032861Y+005266               S0      
317P12V_SW_L        VIA        MD0120PA00X+033242Y+004541               S0      
317P12V_SW_L        VIA        MD0120PA00X+033251Y+004163               S0      
317P12V_SW_L        VIA        MD0120PA00X+033257Y+004903               S0      
317P12V_SW_L        VIA        MD0120PA00X+033261Y+005266               S0      
317P5V_SW_R                     D0340PA01X+046964Y+022426               S0      
317P5V_SW_R                     D0340PA01X+049430Y+015830               S0      
317P5V_SW_R                     D0240PA01X+030780Y+020600               S0      
317P5V_SW_R                     D0240PA01X+030780Y+020950               S0      
327P5V_SW_R                           A01X+030980Y+020050X0450Y0550     S0      
327P5V_SW_R                           A01X+030980Y+019250X0450Y0550     S0      
317P5V_SW_R                     D0197PA00X+046933Y+020374               S0      
317P5V_SW_R                     D0197PA00X+047433Y+020374               S0      
317P5V_SW_R                     D0197PA00X+046933Y+013799               S0      
317P5V_SW_R                     D0197PA00X+047433Y+013799               S0      
327P5V_SW_R                           A01X+032297Y+019992X0450Y0550     S0      
327P5V_SW_R                           A06X+030913Y+018855X0650Y0250     S0      
327P5V_SW_R                           A06X+030913Y+019355X0650Y0250     S0      
327P5V_SW_R                           A06X+030913Y+019855X0650Y0250     S0      
327P5V_SW_R                           A06X+030913Y+020355X0650Y0250     S0      
317P5V_SW_R         VIA        MD0280PA01X+032178Y+019129               S0      
317P5V_SW_R         VIA        MD0120PA00X+031450Y+018850               S0      
317P5V_SW_R         VIA        MD0120PA00X+031450Y+019350               S0      
317P5V_SW_R         VIA        MD0120PA00X+031450Y+019850               S0      
317P5V_SW_R         VIA        MD0120PA00X+031450Y+020350               S0      
317P5V_SW_R         VIA        MD0120PA00X+031850Y+018850               S0      
317P5V_SW_R         VIA        MD0120PA00X+031850Y+019350               S0      
317P5V_SW_R         VIA        MD0120PA00X+031850Y+019850               S0      
317P5V_SW_R         VIA        MD0120PA00X+031850Y+020350               S0      
317P5V                          D0240PA01X+004830Y+007950               S0      
317P5V                          D0240PA01X+004830Y+007600               S0      
327P5V                                A01X+027389Y+004856X0450Y0550     S0      
327P5V                                A01X+033057Y+019992X0450Y0550     S0      
317P5V                          D0240PA06X+030044Y+005473               S0      
317P5V                          D0340PA06X+028773Y+005856               S0      
317P5V                          D0240PA06X+051960Y+010678               S0      
327P5V                                A06X+052156Y+010103X0450Y0550     S0      
327P5V                                A06X+005472Y+007992X0630Y0240     S0      
317P5V                          D0460PA00X+052039Y+008681               S0      
327P5V                                A06X+028750Y+005250X0650Y0250     S0      
327P5V                                A06X+028750Y+004750X0650Y0250     S0      
327P5V                                A06X+028750Y+004250X0650Y0250     S0      
327P5V                                A06X+032913Y+020355X0650Y0250     S0      
327P5V                                A06X+032913Y+019855X0650Y0250     S0      
327P5V                                A06X+032913Y+019355X0650Y0250     S0      
317P5V              VIA        MD0120PA00X+027828Y+004781               S0      
317P5V              VIA        MD0120PA00X+027841Y+005525               S0      
317P5V              VIA        MD0120PA00X+027846Y+005144               S0      
317P5V              VIA        MD0120PA00X+028196Y+004775               S0      
317P5V              VIA        MD0120PA00X+028209Y+005518               S0      
317P5V              VIA        MD0120PA00X+028215Y+005138               S0      
317P5V              VIA        MD0120PA00X+033500Y+019350               S0      
317P5V              VIA        MD0120PA00X+033500Y+019850               S0      
317P5V              VIA        MD0120PA00X+033500Y+020350               S0      
317P5V              VIA        MD0120PA00X+033900Y+019350               S0      
317P5V              VIA        MD0120PA00X+033900Y+019850               S0      
317P5V              VIA        MD0120PA00X+033900Y+020350               S0      
317P5V              VIA        MD0120PA00X+005267Y+008335               S0      
317P5V              VIA        MD0120PA00X+005667Y+008335               S0      
317P5V              VIA        MD0120PA00X+006039Y+008393               S0      
317P5V              VIA        MD0120PA00X+006047Y+007982               S0      
317P12V                         D0240PA01X+033115Y+015364               S0      
317P12V                         D0240PA01X+036100Y+004130               S0      
317P12V                         D0220PA01X+035700Y+004120               S0      
317P12V                         D0220PA01X+032715Y+015354               S0      
317P12V                         D0220PA01X+034880Y+002950               S0      
317P12V                         D0220PA01X+031780Y+014200               S0      
327P12V                               A01X+034461Y+004433X0450Y0550     S0      
327P12V                               A01X+033229Y+016213X0450Y0550     S0      
317P12V                         D0240PA06X+048535Y+010679               S0      
327P12V                               A06X+048352Y+010110X0450Y0550     S0      
317P12V                         D0460PA00X+048496Y+008681               S0      
327P12V                               A06X+035863Y+005205X0650Y0250     S0      
327P12V                               A06X+035863Y+004705X0650Y0250     S0      
327P12V                               A06X+035863Y+004205X0650Y0250     S0      
327P12V                               A06X+032900Y+016450X0650Y0250     S0      
327P12V                               A06X+032900Y+015950X0650Y0250     S0      
327P12V                               A06X+032900Y+015450X0650Y0250     S0      
317P12V                         D0220PA06X+033200Y+017970               S0      
317P12V                         D0220PA06X+028508Y+002993               S0      
317P12V             VIA        MD0120PA00X+028664Y+003392               S0      
317P12V             VIA        MD0120PA00X+033200Y+018350               S0      
317P12V             VIA        MD0120PA00X+033670Y+015474               S0      
317P12V             VIA        MD0120PA00X+033678Y+015838               S0      
317P12V             VIA        MD0120PA00X+033678Y+016202               S0      
317P12V             VIA        MD0120PA00X+033678Y+016572               S0      
317P12V             VIA        MD0120PA00X+034070Y+015474               S0      
317P12V             VIA        MD0120PA00X+034078Y+015838               S0      
317P12V             VIA        MD0120PA00X+034078Y+016202               S0      
317P12V             VIA        MD0120PA00X+034078Y+016572               S0      
317P12V             VIA        MD0120PA00X+034870Y+010540               S0      
317P12V             VIA        MD0120PA00X+034897Y+004181               S0      
317P12V             VIA        MD0120PA00X+034909Y+004916               S0      
317P12V             VIA        MD0120PA00X+034910Y+004554               S0      
317P12V             VIA        MD0120PA00X+034923Y+005281               S0      
317P12V             VIA        MD0120PA00X+035057Y+010226               S0      
317P12V             VIA        MD0120PA00X+035083Y+010898               S0      
317P12V             VIA        MD0120PA00X+035250Y+010564               S0      
317P12V             VIA        MD0120PA00X+035297Y+004181               S0      
317P12V             VIA        MD0120PA00X+035309Y+004916               S0      
317P12V             VIA        MD0120PA00X+035310Y+004554               S0      
317P12V             VIA        MD0120PA00X+035323Y+005281               S0      
317P12V             VIA        MD0120PA00X+035458Y+010235               S0      
317P12V             VIA        MD0120PA00X+035483Y+010898               S0      
317P12V             VIA        MD0120PA00X+035650Y+010564               S0      
317P12V             VIA        MD0120PA00X+035882Y+010885               S0      
317SW_SW_R_N_0                  D0240PA01X+033115Y+015004               S0      
317SW_SW_R_N_0                  D0220PA01X+032870Y+014200               S0      
317SW_SW_R_N_0                  D0220PA01X+032715Y+015014               S0      
327SW_SW_R_N_0                        A06X+032900Y+014950X0650Y0250     S0      
327SW_SW_R_N_0                        A06X+032840Y+014150X0400Y0220     S0      
317SW_SW_R_N_0      VIA        MD0100PA00X+033624Y+014895               S0      
317HBA_PRSNT0_N                 D0240PA01X+047990Y+022370               S0      
317HBA_PRSNT0_N                 D0197PA00X+047933Y+020374               S0      
317HBA_PRSNT0_N                 D0220PA01X+048370Y+022380               S0      
327HBA_PRSNT0_N                       A06X+005472Y+007598X0630Y0240     S0      
327HBA_PRSNT0_N                       A06X+031744Y+021975X0160Y0480     S0      
317HBA_PRSNT0_N     VIA        MD0280PA06X+029213Y+021549               S0      
317HBA_PRSNT0_N     VIA        MD0100PA00X+020800Y+009000               S0      
317HBA_PRSNT0_N     VIA        MD0100PA00X+027950Y+011690               S0      
317SW_SW_L_N_0                  D0240PA01X+036100Y+003770               S0      
317SW_SW_L_N_0                  D0220PA01X+036020Y+002950               S0      
317SW_SW_L_N_0                  D0220PA01X+035700Y+003780               S0      
327SW_SW_L_N_0                        A06X+035863Y+003705X0650Y0250     S0      
327SW_SW_L_N_0                        A06X+035890Y+002940X0400Y0220     S0      
317SW_SW_L_N_0      VIA        MD0100PA00X+035890Y+002393               S0      
317SW_SW_L_N_0      VIA        MD0120PA00X+036475Y+003775               S0      
317P3V3                         D0240PA01X+032095Y+004283               S0      
317P3V3                         D0240PA01X+032442Y+004282               S0      
317P3V3                         D0220PA01X+021150Y+007820               S0      
317P3V3                         D0220PA01X+021496Y+003550               S0      
317P3V3                         D0220PA01X+048370Y+022720               S0      
317P3V3                         D0220PA01X+032097Y+003550               S0      
317P3V3                         D0220PA01X+050687Y+016299               S0      
317P3V3                         D0220PA01X+032515Y+003550               S0      
317P3V3                         D0220PA01X+033630Y+002000               S0      
317P3V3                         D0220PA01X+030580Y+013350               S0      
317P3V3                         D0240PA06X+030754Y+005217               S0      
317P3V3                         D0240PA06X+031874Y+005092               S0      
327P3V3                               A06X+031896Y+004040X0160Y0400     S0      
327P3V3                               A06X+031744Y+021325X0160Y0480     S0      
327P3V3                               A06X+030134Y+003295X0160Y0480     S0      
317P3V3             VIA        MD0100PA00X+050687Y+016660               S0      
317P3V3             VIA        MD0100PA00X+021310Y+008350               S0      
317P3V3             VIA        MD0100PA00X+021860Y+003740               S0      
317P3V3             VIA        MD0100PA00X+022031Y+000409               S0      
317P3V3             VIA        MD0100PA00X+025809Y+002179               S0      
317P3V3             VIA        MD0100PA00X+026805Y+000827               S0      
317P3V3             VIA        MD0100PA00X+031517Y+005217               S0      
317P3V3             VIA        MD0100PA00X+007357Y+000409               S0      
317P3V3             VIA        MD0100PA00X+007660Y+006800               S0      
317P3V3             VIA        MD0120PA00X+028055Y+006154               S0      
317P3V3             VIA        MD0120PA00X+028429Y+006151               S0      
317P3V3             VIA        MD0120PA00X+030191Y+012982               S0      
317P3V3             VIA        MD0120PA00X+030200Y+013350               S0      
317P3V3             VIA        MD0120PA00X+031445Y+021325               S0      
317P3V3             VIA        MD0120PA00X+033278Y+002000               S0      
317P3V3             VIA        MD0120PA00X+048010Y+023062               S0      
317P3V3             VIA        MD0120PA00X+048370Y+023052               S0      
327CEXT_P5                            A06X+031640Y+004040X0160Y0400     S0      
317CEXT_P5                      D0340PA06X+031300Y+004630               S0      
317PWR_EN_R_P5V                 D0240PA06X+032803Y+017623               S0      
317PWR_EN_R_P5V                 D0220PA06X+033200Y+017630               S0      
327PWR_EN_R_P5V                       A06X+032913Y+018855X0650Y0250     S0      
317PWR_EN_R_P5V                 D0300PA06X+031923Y+017294               S0      
317PWR_EN_R_P5V     VIA        MD0280PA06X+033749Y+017747               S0      
317PWR_EN_L_P5V                 D0240PA06X+028108Y+002643               S0      
317PWR_EN_L_P5V                 D0220PA06X+028508Y+002653               S0      
327PWR_EN_L_P5V                       A06X+028750Y+003750X0650Y0250     S0      
317PWR_EN_L_P5V                 D0300PA06X+027222Y+002232               S0      
317HDD_ACT_LED0                 D0197PA00X+048433Y+020374               S0      
327HDD_ACT_LED0                       A06X+005472Y+004843X0630Y0240     S0      
317HDD_ACT_LED0     VIA        MD0280PA06X+047055Y+011232               S0      
317HDD_ACT_LED0     VIA        MD0120PA00X+034742Y+000857               S0      
317HDD_ACT_LED0     VIA        MD0120PA00X+006371Y+004843               S0      
317HDD_ACT_LED1                 D0197PA00X+048433Y+013799               S0      
327HDD_ACT_LED1                       A06X+005472Y+004449X0630Y0240     S0      
317HDD_ACT_LED1     VIA        MD0280PA06X+045951Y+011318               S0      
317HDD_ACT_LED1     VIA        MD0120PA00X+035048Y+001077               S0      
317HDD_ACT_LED1     VIA        MD0120PA00X+006501Y+004343               S0      
317HDD_ACT_LED2                 D0197PA00X+019329Y+005453               S0      
327HDD_ACT_LED2                       A06X+005472Y+004055X0630Y0240     S0      
317HDD_ACT_LED2     VIA        MD0100PA00X+007510Y+003670               S0      
317HDD_ACT_LED3                 D0197PA00X+019329Y+001004               S0      
327HDD_ACT_LED3                       A06X+005472Y+003661X0630Y0240     S0      
317HDD_ACT_LED3     VIA        MD0100PA00X+007464Y+002915               S0      
317SW_SW_R_0                    D0220PA01X+032530Y+014200               S0      
317SW_SW_R_0                    D0220PA01X+032120Y+014200               S0      
327SW_SW_R_0                          A06X+031206Y+014070X0160Y0400     S0      
327SW_SW_R_0                          A06X+031940Y+014150X0400Y0220     S0      
317SW_SW_R_0        VIA        MD0100PA00X+032204Y+014720               S0      
317SW_SW_L_0                    D0220PA01X+035680Y+002950               S0      
317SW_SW_L_0                    D0220PA01X+035220Y+002950               S0      
327SW_SW_L_0                          A06X+034256Y+002770X0160Y0400     S0      
327SW_SW_L_0                          A06X+034990Y+002940X0400Y0220     S0      
317SW_SW_L_0        VIA        MD0100PA00X+035104Y+003475               S0      
317HBA_MB_RX_P1                 D0197PA00X+040433Y+013799               S0      
327HBA_MB_RX_P1                       A06X+029758Y+008398X0470Y0140     S0      
317HBA_MB_RX_N1                 D0197PA00X+039933Y+013799               S0      
327HBA_MB_RX_N1                       A06X+029758Y+008693X0470Y0140     S0      
317HBA_MB_RX_P3                 D0197PA00X+011329Y+001004               S0      
327HBA_MB_RX_P3                       A06X+029758Y+009284X0470Y0140     S0      
317HBA_MB_RX_N3                 D0197PA00X+010829Y+001004               S0      
327HBA_MB_RX_N3                       A06X+029758Y+009579X0470Y0140     S0      
317HBA_MB_RX_P0                 D0197PA00X+040433Y+020374               S0      
327HBA_MB_RX_P0                       A06X+030821Y+008398X0470Y0140     S0      
317HBA_MB_RX_N0                 D0197PA00X+039933Y+020374               S0      
327HBA_MB_RX_N0                       A06X+030821Y+008693X0470Y0140     S0      
317HBA_MB_RX_P2                 D0197PA00X+011329Y+005453               S0      
327HBA_MB_RX_P2                       A06X+030821Y+009284X0470Y0140     S0      
317HBA_MB_RX_N2                 D0197PA00X+010829Y+005453               S0      
327HBA_MB_RX_N2                       A06X+030821Y+009579X0470Y0140     S0      
317HBA_MB_TX_P1                 D0197PA00X+038433Y+013799               S0      
327HBA_MB_TX_P1                       A06X+032211Y+008398X0470Y0140     S0      
317HBA_MB_TX_P1     VIA        MD0100PA00X+032711Y+008333               S0      
317HBA_MB_TX_N1                 D0197PA00X+038933Y+013799               S0      
327HBA_MB_TX_N1                       A06X+032211Y+008693X0470Y0140     S0      
317HBA_MB_TX_N1     VIA        MD0100PA00X+032711Y+008733               S0      
317HBA_MB_TX_P3                 D0197PA00X+009329Y+001004               S0      
327HBA_MB_TX_P3                       A06X+032211Y+009284X0470Y0140     S0      
317HBA_MB_TX_P3     VIA        MD0100PA00X+032940Y+010121               S0      
317HBA_MB_TX_N3                 D0197PA00X+009829Y+001004               S0      
327HBA_MB_TX_N3                       A06X+032211Y+009579X0470Y0140     S0      
317HBA_MB_TX_N3     VIA        MD0100PA00X+032540Y+010121               S0      
317HBA_MB_TX_P0                 D0197PA00X+038433Y+020374               S0      
327HBA_MB_TX_P0                       A06X+033274Y+008398X0470Y0140     S0      
317HBA_MB_TX_P0     VIA        MD0100PA00X+034303Y+008345               S0      
317HBA_MB_TX_N0                 D0197PA00X+038933Y+020374               S0      
327HBA_MB_TX_N0                       A06X+033274Y+008693X0470Y0140     S0      
317HBA_MB_TX_N0     VIA        MD0100PA00X+034303Y+008745               S0      
317HBA_MB_TX_P2                 D0197PA00X+009329Y+005453               S0      
327HBA_MB_TX_P2                       A06X+033274Y+009284X0470Y0140     S0      
317HBA_MB_TX_P2     VIA        MD0100PA00X+034087Y+009231               S0      
317HBA_MB_TX_N2                 D0197PA00X+009829Y+005453               S0      
327HBA_MB_TX_N2                       A06X+033274Y+009579X0470Y0140     S0      
317HBA_MB_TX_N2     VIA        MD0100PA00X+034087Y+009631               S0      
317P5V_R_E1                     D0240PA06X+030754Y+005729               S0      
317P5V_R_E1                     D0340PA06X+029333Y+005856               S0      
327P5V_R_E1                           A06X+031662Y+005670X0400Y0220     S0      
327PWR_EN_R_N                         A06X+030950Y+014070X0160Y0400     S0      
327PWR_EN_R_N                         A06X+032256Y+021325X0160Y0480     S0      
317PWR_EN_R_N                   D0300PA06X+031535Y+018044               S0      
317PWR_EN_R_N       VIA        MD0100PA00X+031050Y+018433               S0      
317PWR_EN_R_N       VIA        MD0120PA00X+030950Y+014500               S0      
317PWR_EN_L_DELAY               D0220PA01X+032515Y+003210               S0      
327PWR_EN_L_DELAY                     A06X+034000Y+002770X0160Y0400     S0      
327PWR_EN_L_DELAY                     A06X+031384Y+004040X0160Y0400     S0      
317PWR_EN_L_DELAY               D0300PA06X+026835Y+002982               S0      
317PWR_EN_L_DELAY   VIA        MD0280PA06X+032820Y+003224               S0      
317PWR_EN_L_DELAY   VIA        MD0100PA00X+027355Y+003711               S0      
317PWR_EN_L_DELAY   VIA        MD0100PA00X+032470Y+001630               S0      
3175V_PRE_2                     D0340PA01X+018270Y+007500               S0      
3175V_PRE_2                     D0197PA00X+017329Y+005453               S0      
31712V_PRE_3                    D0340PA01X+022092Y+003390               S0      
31712V_PRE_3                    D0197PA00X+020329Y+001004               S0      
31712V_PRE_2                    D0340PA01X+021659Y+007496               S0      
31712V_PRE_2                    D0197PA00X+020329Y+005453               S0      
317PWR_EN_D_0                   D0220PA01X+030920Y+013350               S0      
327PWR_EN_D_0                         A06X+030950Y+013330X0160Y0400     S0      
327PWR_EN_D_0                         A06X+030694Y+013330X0160Y0400     S0      
317PWR_EN_D_0       VIA        MD0100PA00X+030925Y+012744               S0      
317PWR_EN_D_2                   D0220PA01X+033970Y+002000               S0      
327PWR_EN_D_2                         A06X+034000Y+002030X0160Y0400     S0      
327PWR_EN_D_2                         A06X+033744Y+002030X0160Y0400     S0      
317PWR_EN_D_2       VIA        MD0100PA00X+034000Y+001467               S0      
317ENIN_P1                      D0220PA01X+032097Y+003210               S0      
327ENIN_P1                            A06X+031896Y+003300X0160Y0400     S0      
317ENIN_P1          VIA        MD0100PA00X+032210Y+002660               S0      
317PWR_EN_L                     D0220PA01X+030530Y+003200               S0      
327PWR_EN_L                           A06X+030646Y+003295X0160Y0480     S0      
317PWR_EN_L         VIA        MD0100PA00X+030390Y+002890               S0      
317VIN_P3                       D0220PA01X+030870Y+003200               S0      
317VIN_P3                       D0220PA01X+031330Y+003200               S0      
327VIN_P3                             A06X+031384Y+003300X0160Y0400     S0      
317VIN_P3           VIA        MD0100PA00X+031390Y+002720               S0      
3175V_PRE_1                     D0340PA01X+048870Y+015830               S0      
3175V_PRE_1                     D0197PA00X+046433Y+013799               S0      
3175V_PRE_0                     D0340PA01X+046404Y+022426               S0      
3175V_PRE_0                     D0197PA00X+046433Y+020374               S0      
31712V_PRE_1                    D0340PA01X+051170Y+015850               S0      
31712V_PRE_1                    D0197PA00X+049433Y+013799               S0      
31712V_PRE_0                    D0340PA01X+049185Y+022405               S0      
31712V_PRE_0                    D0197PA00X+049433Y+020374               S0      
3175V_PRE_3                     D0340PA01X+018690Y+003210               S0      
3175V_PRE_3                     D0197PA00X+017329Y+001004               S0      
999
